# BASEBOARD_FAB2 (Tioga Pass) — schematic netlist excerpt (pin names and nets, part order shuffled) for the footprints in the layout excerpt that follows; sources: Cadence DE-HDL packaged netlist, KiCad conversion of Wiwynn_Tioga_Pass_MB.brd

R1G17  RES  1.00K 1% CHIP  pkg 0402  page 100 : A = M_J_VREF ; B = GND
C3F3  CAP  10UF 4V 20% X6S  pkg 0603LF  page 233 : A = PVPP_GHJ ; B = GND

CR25W1  DIODEAC_DUAL_ARRAY  ESD3V3U4ULC IC  pkg SM9  page 252
  AC0  = V_IO_B_J
  AC1  = V_IO_G_J
  GND(0)  = GND
  AC2  = V_IO_R_J
  AC3  = NC
  OUT3  = NC
  OUT2  = V_IO_R_J
  OUT1  = V_IO_G_J
  OUT0  = V_IO_B_J

(kicad_pcb
	(version 20260206)
	(generator "pcbnew")
	(generator_version "10.0")
	(general
		(thickness 1.6)
		(legacy_teardrops no)
	)
	(paper "A4")
	(title_block
		(title "Wiwynn_Tioga_Pass_MB.brd")
		(comment 1 "Tioga Pass / footprints 1822-1824 of 4770")
	)
	(layers
		(0 "F.Cu" signal "TOP")
		(4 "In1.Cu" signal "L2GND")
		(6 "In2.Cu" signal "L3")
		(8 "In3.Cu" signal "L4GND")
		(10 "In4.Cu" signal "L5")
		(12 "In5.Cu" signal "L6GND")
		(14 "In6.Cu" signal "L7VCC")
		(16 "In7.Cu" signal "L8VCC")
		(18 "In8.Cu" signal "L9GND")
		(20 "In9.Cu" signal "L10")
		(22 "In10.Cu" signal "L11GND")
		(24 "In11.Cu" signal "L12")
		(26 "In12.Cu" signal "L13GND")
		(2 "B.Cu" signal "BOTTOM")
		(9 "F.Adhes" user "F.Adhesive")
		(11 "B.Adhes" user "B.Adhesive")
		(13 "F.Paste" user "Package Geometry/Pastemask Top")
		(15 "B.Paste" user "Package Geometry/Pastemask Bottom")
		(5 "F.SilkS" user "Ref Des/Silkscreen Top")
		(7 "B.SilkS" user "Ref Des/Silkscreen Bottom")
		(1 "F.Mask" user "Board Geometry/Soldermask Top")
		(3 "B.Mask" user "Board Geometry/Soldermask Bottom")
		(17 "Dwgs.User" user "User.Drawings")
		(19 "Cmts.User" user "User.Comments")
		(21 "Eco1.User" user "User.Eco1")
		(23 "Eco2.User" user "User.Eco2")
		(25 "Edge.Cuts" user "Board Geometry/Outline")
		(27 "Margin" user)
		(31 "F.CrtYd" user "Package Geometry/Place Bound Top")
		(29 "B.CrtYd" user "Package Geometry/Place Bound Bottom")
		(35 "F.Fab" user "Ref Des/Assembly Top")
		(33 "B.Fab" user "Ref Des/Assembly Bottom")
	)
	(footprint ""
		(layer "F.Cu")
		(at 153.5303 -22.7457 -90)
		(property "Reference" "C3F3"
			(at 0 0 270)
			(layer "F.SilkS")
			(hide yes)
			(effects
				(font
					(size 1.27 1.27)
				)
			)
		)
		(property "Value" ""
			(at 0 0 270)
			(layer "F.Fab")
			(effects
				(font
					(size 1.27 1.27)
				)
			)
		)
		(duplicate_pad_numbers_are_jumpers no)
		(fp_poly
			(pts
				(xy -0.4953 -0.2032) (xy 0.4953 -0.2032) (xy 0.4953 1.6002) (xy -0.4953 1.6002)
			)
			(stroke
				(width 0)
				(type default)
			)
			(fill no)
			(layer "F.CrtYd")
		)
		(fp_line
			(start -0.4953 1.6002)
			(end -0.4953 -0.2032)
			(stroke
				(width 0.1)
				(type default)
			)
			(layer "F.Fab")
		)
		(fp_line
			(start 0.4953 1.6002)
			(end -0.4953 1.6002)
			(stroke
				(width 0.1)
				(type default)
			)
			(layer "F.Fab")
		)
		(fp_line
			(start -0.4953 -0.2032)
			(end 0.4953 -0.2032)
			(stroke
				(width 0.1)
				(type default)
			)
			(layer "F.Fab")
		)
		(fp_line
			(start 0.4953 -0.2032)
			(end 0.4953 1.6002)
			(stroke
				(width 0.1)
				(type default)
			)
			(layer "F.Fab")
		)
		(pad "1" smd rect
			(at 0 0 270)
			(size 0.762 0.889)
			(layers "F.Cu" "F.Mask" "F.Paste")
			(net "PVPP_GHJ")
		)
		(pad "2" smd rect
			(at 0 1.397 270)
			(size 0.762 0.889)
			(layers "F.Cu" "F.Mask" "F.Paste")
			(net "GND")
		)
		(zone
			(layer "F.Cu")
			(hatch none 0.5)
			(connect_pads
				(clearance 0)
			)
			(min_thickness 0.25)
			(keepout
				(tracks not_allowed)
				(vias allowed)
				(pads allowed)
				(copperpour not_allowed)
				(footprints allowed)
			)
			(placement
				(enabled no)
				(sheetname "")
			)
			(fill
				(thermal_gap 0.5)
				(thermal_bridge_width 0.5)
				(island_removal_mode 0)
			)
			(polygon
				(pts
					(xy 153.0858 -23.1267) (xy 153.0858 -22.3647) (xy 152.5778 -22.3647) (xy 152.5778 -23.1267)
				)
			)
		)
	)
	(footprint ""
		(layer "F.Cu")
		(at 29.591 -2.877312 180)
		(property "Reference" "R1G17"
			(at 0 0 180)
			(layer "F.SilkS")
			(hide yes)
			(effects
				(font
					(size 1.27 1.27)
				)
			)
		)
		(property "Value" ""
			(at 0 0 180)
			(layer "F.Fab")
			(effects
				(font
					(size 1.27 1.27)
				)
			)
		)
		(duplicate_pad_numbers_are_jumpers no)
		(fp_poly
			(pts
				(xy -0.2794 -0.1016) (xy 0.2794 -0.1016) (xy 0.2794 0.9906) (xy -0.2794 0.9906)
			)
			(stroke
				(width 0)
				(type default)
			)
			(fill no)
			(layer "F.CrtYd")
		)
		(fp_line
			(start 0.2794 0.9906)
			(end 0.2794 -0.1016)
			(stroke
				(width 0.1)
				(type default)
			)
			(layer "F.Fab")
		)
		(fp_line
			(start 0.2794 -0.1016)
			(end -0.2794 -0.1016)
			(stroke
				(width 0.1)
				(type default)
			)
			(layer "F.Fab")
		)
		(fp_line
			(start -0.2794 0.9906)
			(end 0.2794 0.9906)
			(stroke
				(width 0.1)
				(type default)
			)
			(layer "F.Fab")
		)
		(fp_line
			(start -0.2794 -0.1016)
			(end -0.2794 0.9906)
			(stroke
				(width 0.1)
				(type default)
			)
			(layer "F.Fab")
		)
		(pad "1" smd rect
			(at 0 0 180)
			(size 0.508 0.508)
			(layers "F.Cu" "F.Mask" "F.Paste")
			(net "M_J_VREF")
		)
		(pad "2" smd rect
			(at 0 0.889 180)
			(size 0.508 0.508)
			(layers "F.Cu" "F.Mask" "F.Paste")
			(net "GND")
		)
		(zone
			(layer "F.Cu")
			(hatch none 0.5)
			(connect_pads
				(clearance 0)
			)
			(min_thickness 0.25)
			(keepout
				(tracks not_allowed)
				(vias allowed)
				(pads allowed)
				(copperpour not_allowed)
				(footprints allowed)
			)
			(placement
				(enabled no)
				(sheetname "")
			)
			(fill
				(thermal_gap 0.5)
				(thermal_bridge_width 0.5)
				(island_removal_mode 0)
			)
			(polygon
				(pts
					(xy 29.845 -3.512312) (xy 29.337 -3.512312) (xy 29.337 -3.131312) (xy 29.845 -3.131312)
				)
			)
		)
		(zone
			(layer "F.Cu")
			(hatch none 0.5)
			(connect_pads
				(clearance 0)
			)
			(min_thickness 0.25)
			(keepout
				(tracks allowed)
				(vias not_allowed)
				(pads allowed)
				(copperpour not_allowed)
				(footprints allowed)
			)
			(placement
				(enabled no)
				(sheetname "")
			)
			(fill
				(thermal_gap 0.5)
				(thermal_bridge_width 0.5)
				(island_removal_mode 0)
			)
			(polygon
				(pts
					(xy 29.845 -3.131312) (xy 29.337 -3.131312) (xy 29.337 -3.512312) (xy 29.845 -3.512312)
				)
			)
		)
	)
	(footprint ""
		(layer "F.Cu")
		(at 490.6137 -35.687)
		(property "Reference" "CR25W1"
			(at -1.495806 -1.067816 0)
			(unlocked yes)
			(layer "F.SilkS")
			(effects
				(font
					(size 0.4064 0.254)
					(thickness 0.1524)
				)
				(justify left)
			)
		)
		(property "Value" ""
			(at 0 0 0)
			(layer "F.Fab")
			(effects
				(font
					(size 1.27 1.27)
				)
			)
		)
		(duplicate_pad_numbers_are_jumpers no)
		(fp_circle
			(center -0.589026 -0.5334)
			(end -0.462026 -0.5334)
			(stroke
				(width 0.254)
				(type default)
			)
			(fill no)
			(layer "F.SilkS")
		)
		(fp_rect
			(start -0.225552 2.167382)
			(end 0.809498 -0.167386)
			(stroke
				(width 0)
				(type default)
			)
			(fill no)
			(layer "F.CrtYd")
		)
		(fp_line
			(start -0.225552 -0.167386)
			(end 0.809498 -0.167386)
			(stroke
				(width 0.1)
				(type default)
			)
			(layer "F.Fab")
		)
		(fp_line
			(start -0.225552 2.167382)
			(end -0.225552 -0.167386)
			(stroke
				(width 0.1)
				(type default)
			)
			(layer "F.Fab")
		)
		(fp_line
			(start 0.809498 -0.167386)
			(end 0.809498 2.167382)
			(stroke
				(width 0.1)
				(type default)
			)
			(layer "F.Fab")
		)
		(fp_line
			(start 0.809498 2.167382)
			(end -0.225552 2.167382)
			(stroke
				(width 0.1)
				(type default)
			)
			(layer "F.Fab")
		)
		(fp_circle
			(center -0.589026 -0.5334)
			(end -0.462026 -0.5334)
			(stroke
				(width 0.254)
				(type default)
			)
			(fill no)
			(layer "F.Fab")
		)
		(pad "1" smd rect
			(at 0 0)
			(size 0.3556 0.2032)
			(layers "F.Cu" "F.Mask" "F.Paste")
			(net "V_IO_B_J")
		)
		(pad "2" smd rect
			(at 0 0.500126)
			(size 0.3556 0.2032)
			(layers "F.Cu" "F.Mask" "F.Paste")
			(net "V_IO_G_J")
		)
		(pad "3" smd rect
			(at 0.2921 0.999998)
			(size 0.9398 0.4064)
			(layers "F.Cu" "F.Mask" "F.Paste")
			(net "GND")
		)
		(pad "4" smd rect
			(at 0 1.500124)
			(size 0.3556 0.2032)
			(layers "F.Cu" "F.Mask" "F.Paste")
			(net "V_IO_R_J")
		)
		(pad "5" smd rect
			(at 0 1.999996)
			(size 0.3556 0.2032)
			(layers "F.Cu" "F.Mask" "F.Paste")
			(net "Net_6484")
		)
		(pad "6" smd rect
			(at 0.583946 1.999996)
			(size 0.3556 0.2032)
			(layers "F.Cu" "F.Mask" "F.Paste")
			(net "Net_6483")
		)
		(pad "7" smd rect
			(at 0.583946 1.500124)
			(size 0.3556 0.2032)
			(layers "F.Cu" "F.Mask" "F.Paste")
			(net "V_IO_R_J")
		)
		(pad "8" smd rect
			(at 0.583946 0.500126)
			(size 0.3556 0.2032)
			(layers "F.Cu" "F.Mask" "F.Paste")
			(net "V_IO_G_J")
		)
		(pad "9" smd rect
			(at 0.583946 0)
			(size 0.3556 0.2032)
			(layers "F.Cu" "F.Mask" "F.Paste")
			(net "V_IO_B_J")
		)
	)
)
